FILE_TYPE = CONNECTIVITY;
{Allegro Design Entry HDL 17.4-2019 S026 (4007227) 1/17/2022}
"PAGE_NUMBER" = 267;
0"NC";
1"AGND_HSC\g";
2"AGND_HSC\g";
3"P3V3_AUX\g";
4"HSC_VDD\g";
5"GND\g";
6"AGND_HSC\g";
7"P12V_AUX\g";
8"AGND_HSC\g";
9"AGND_HSC\g";
10"AGND_HSC\g";
11"HSC_VDD_R";
12"HSC_FLT_TYPE";
13"HSC_SCREF";
14"HSC_OCREF";
15"SMB_SML1_PMBUS_HSC_R_SDA";
16"SMB_SML1_PMBUS_HSC_L_SCL";
17"SMB_SML1_PMBUS_HSC_SCL";
18"SMB_SML1_PMBUS_HSC_SDA";
19"IRQ_SML1_PMBUS_ALERT_N";
20"HSC_VIN_UVW_N";
21"HSC_EN_R";
22"IRQ_SML1_PMBUS_ALERT";
23"HSC_ON_R";
24"HSC_EN";
25"HSC_ON";
26"HSC_VDD18";
27"HSC_ADDR";
28"HSC_D_OC_R";
29"IRQ_HSC_FAULT_N";
30"HSC_D_OC";
31"HSC_FAULT";
32"HSC_MODE";
33"HSC_VTEMP";
34"HSC_SS";
35"HSC_CS";
36"HSC_IMON";
37"AGND_HSC\g";
38"AGND_HSC\g";
39"HSC_VDD\g";
40"AGND_HSC\g";
41"AGND_HSC\g";
42"AGND_HSC\g";
43"GND\g";
44"HSC_VDD\g";
45"MB0_P12V_STBY_PWRGD";
46"HSC_VSENSE";
47"AGND_HSC\g";
48"P12V_AUX\g";
49"HSC_VOSEN";
50"P12V_PSU\g";
%"UNIVERSAL_GND"
"1","(-12850,1550)","0","pure_quanta_power","I17";
;
HDL_POWER"AGND_HSC"
CDS_LIB"pure_quanta_power";
"A"1;
%"UNIVERSAL_GND"
"1","(-9975,1250)","0","pure_quanta_power","I21";
;
HDL_POWER"AGND_HSC"
CDS_LIB"pure_quanta_power";
"A"2;
%"Q_RES"
"2","(-9975,1450)","0","pure_quanta","I22";
;
LOCATION"R1117"
$SEC"1"
CDS_SEC"1"
VALUE"6.19K"
ROOM"HSC BOM1"
TOLERANCE"1%"
WATTAGE"1/16W"
MATERIAL"CHIP"
PACK_TYPE"0402LF"
CDS_LIB"pure_quanta"
PART_NUMBER"CS26192FB03";
"A"
$PN"1"45;
"B"
$PN"2"2;
%"Q_RES"
"1","(-14625,2500)","0","pure_quanta","I24";
;
LOCATION"R3924"
$SEC"1"
CDS_SEC"1"
PACK_TYPE"0402LF"
ROOM"HSC BOM1"
TOLERANCE"5%"
VALUE"0"
WATTAGE"1/16W"
MATERIAL"CHIP"
CDS_LIB"pure_quanta"
PART_NUMBER"CS00002JB13";
"B"
$PN"2"22;
"A"
$PN"1"19;
%"Q_CAP"
"1","(-15425,3625)","0","pure_quanta","I27";
;
LOCATION"PC2186"
$SEC"1"
CDS_SEC"1"
PACK_TYPE"C0402"
MATERIAL"X6S"
VALUE"1UF"
VOLTAGE"25V"
ROOM"HSC BOM1"
TOLERANCE"10%"
CDS_LIB"pure_quanta"
PART_NUMBER"CH5104KEB02";
"B"
$PN"2"37;
"A"
$PN"1"11;
%"UNIVERSAL_GND"
"1","(-14925,3350)","0","pure_quanta_power","I29";
;
HDL_POWER"AGND_HSC"
CDS_LIB"pure_quanta_power";
"A"37;
%"Q_CAP"
"1","(-14925,3600)","0","pure_quanta","I30";
;
LOCATION"PC2187"
$SEC"1"
CDS_SEC"1"
MATERIAL"X6S"
PACK_TYPE"C0402"
VOLTAGE"25V"
VALUE"1UF"
ROOM"HSC BOM1"
CDS_LIB"pure_quanta"
TOLERANCE"10%"
PART_NUMBER"CH5104KEB02";
"B"
$PN"2"37;
"A"
$PN"1"11;
%"Q_RES"
"1","(-14225,2675)","1","pure_quanta","I34";
;
LOCATION"R3925"
$SEC"1"
CDS_SEC"1"
TOLERANCE"1%"
VALUE"1K"
PACK_TYPE"0402LF"
WATTAGE"1/16W"
MATERIAL"CHIP"
ROOM"HSC BOM1"
CDS_LIB"pure_quanta"
PART_NUMBER"CS21002FB06";
"B"
$PN"2"3;
"A"
$PN"1"22;
%"UNIVERSAL_POWER"
"1","(-14225,2850)","0","pure_quanta_power","I35";
;
HDL_POWER"P3V3_AUX"
CDS_LIB"pure_quanta_power";
"A"3;
%"Q_RES"
"1","(-13675,3075)","0","pure_quanta","I36";
;
LOCATION"R1714"
$SEC"1"
CDS_SEC"1"
VALUE"0"
ROOM"HSC BOM1"
WATTAGE"1/16W"
TOLERANCE"5%"
PACK_TYPE"0402LF"
MATERIAL"CHIP"
CDS_LIB"pure_quanta"
PART_NUMBER"CS00002JB13";
"B"
$PN"2"15;
"A"
$PN"1"18;
%"Q_RES"
"1","(-13675,3175)","0","pure_quanta","I37";
;
LOCATION"R3909"
$SEC"1"
CDS_SEC"1"
WATTAGE"1/16W"
VALUE"33.2"
PACK_TYPE"0402LF"
TOLERANCE"1%"
MATERIAL"CHIP"
ROOM"HSC BOM1"
CDS_LIB"pure_quanta"
PART_NUMBER"CS03322FB03";
"B"
$PN"2"16;
"A"
$PN"1"17;
%"UNIVERSAL_GND"
"1","(-13700,3575)","0","pure_quanta_power","I38";
;
HDL_POWER"AGND_HSC"
CDS_LIB"pure_quanta_power";
"A"38;
%"Q_RES"
"1","(-15225,4050)","1","pure_quanta","I39";
;
LOCATION"PR2149"
$SEC"1"
CDS_SEC"1"
VALUE"0"
MATERIAL"CHIP"
WATTAGE"1/16W"
PACK_TYPE"0402LF"
TOLERANCE"5%"
ROOM"HSC BOM1"
CDS_LIB"pure_quanta"
PART_NUMBER"CS00002JB13";
"B"
$PN"2"4;
"A"
$PN"1"11;
%"UNIVERSAL_POWER"
"1","(-15225,4275)","0","pure_quanta_power","I41";
;
HDL_POWER"HSC_VDD"
BOM_COST"MIO_VRD_SB"
CDS_LIB"pure_quanta_power";
"A"4;
%"GND"
"1","(-14225,3975)","0","pure_quanta_power","I42";
;
CDS_LIB"pure_quanta_power"
SIZE"1B"
HDL_POWER"GND";
"A<SIZE-1..0>\NAC"5;
%"UNIVERSAL_POWER"
"1","(-14225,4975)","0","pure_quanta_power","I45";
;
HDL_POWER"P12V_PSU"
CDS_LIB"pure_quanta_power"
BOM_COST"MIO_VRD_SB";
"A"50;
%"Q_CAP"
"1","(-14225,4350)","0","pure_quanta","I46";
;
LOCATION"PC2188"
$SEC"1"
CDS_SEC"1"
PACK_TYPE"C0402"
MATERIAL"X6S"
VOLTAGE"25V"
VALUE"1UF"
ROOM"HSC BOM1"
TOLERANCE"10%"
CDS_LIB"pure_quanta"
PART_NUMBER"CH5104KEB02";
"B"
$PN"2"5;
"A"
$PN"1"50;
%"Q_RES"
"2","(-13700,3900)","0","pure_quanta","I47";
;
LOCATION"PR3927"
$SEC"1"
CDS_SEC"1"
TOLERANCE"0.1%"
PACK_TYPE"0402LF"
MATERIAL"CHIP"
WATTAGE"1/16W"
ROOM"HSC BOM1"
VALUE"4.99K"
CDS_LIB"pure_quanta"
PART_NUMBER"CS24992BB04";
"A"
$PN"1"46;
"B"
$PN"2"38;
%"Q_RES"
"2","(-13700,4350)","0","pure_quanta","I48";
;
LOCATION"PR3926"
$SEC"1"
CDS_SEC"1"
PACK_TYPE"0402LF"
VALUE"75K"
ROOM"HSC BOM1"
TOLERANCE"0.1%"
WATTAGE"1/16W"
MATERIAL"CHIP"
CDS_LIB"pure_quanta"
PART_NUMBER"CS37502BB01";
"A"
$PN"1"50;
"B"
$PN"2"46;
%"UNIVERSAL_GND"
"1","(-13325,1875)","0","pure_quanta_power","I49";
;
HDL_POWER"AGND_HSC"
CDS_LIB"pure_quanta_power";
"A"6;
%"Q_CAP"
"1","(-13325,2175)","0","pure_quanta","I50";
;
LOCATION"PC2103"
$SEC"1"
CDS_SEC"1"
VALUE"1UF"
VOLTAGE"25V"
MATERIAL"X6S"
PACK_TYPE"C0402"
ROOM"HSC BOM1"
CDS_LIB"pure_quanta"
TOLERANCE"10%"
PART_NUMBER"CH5104KEB02";
"B"
$PN"2"6;
"A"
$PN"1"26;
%"Q_RES"
"1","(-13100,2525)","0","pure_quanta","I51";
;
LOCATION"PR3928"
$SEC"1"
CDS_SEC"1"
WATTAGE"1/16W"
PACK_TYPE"0402LF"
MATERIAL"CHIP"
TOLERANCE"5%"
VALUE"0"
ROOM"HSC BOM1"
CDS_LIB"pure_quanta"
PART_NUMBER"CS00002JB13";
"B"
$PN"2"23;
"A"
$PN"1"25;
%"Q_RES"
"1","(-12850,1750)","1","pure_quanta","I52";
;
LOCATION"PR3930"
$SEC"1"
CDS_SEC"1"
VALUE"0"
TOLERANCE"5%"
PACK_TYPE"0402LF"
MATERIAL"CHIP"
WATTAGE"1/16W"
ROOM"HSC BOM1"
CDS_LIB"pure_quanta"
PART_NUMBER"CS00002JB13";
"B"
$PN"2"27;
"A"
$PN"1"1;
%"Q_RES"
"1","(-12850,2150)","1","pure_quanta","I53";
;
LOCATION"PR3929"
$SEC"1"
CDS_SEC"1"
MATERIAL"EMPTY"
PACK_TYPE"0402LF"
WATTAGE"1/16W"
TOLERANCE"1%"
VALUE"1K"
ROOM"HSC BOM1"
CDS_LIB"pure_quanta"
PART_NUMBER"CS21002FB06";
"B"
$PN"2"26;
"A"
$PN"1"27;
%"Q_RES"
"1","(-13100,2650)","0","pure_quanta","I54";
;
LOCATION"R2586"
$SEC"1"
CDS_SEC"1"
VALUE"0"
MATERIAL"CHIP"
ROOM"HSC BOM1"
WATTAGE"1/16W"
PACK_TYPE"0402LF"
TOLERANCE"5%"
CDS_LIB"pure_quanta"
PART_NUMBER"CS00002JB13";
"B"
$PN"2"21;
"A"
$PN"1"24;
%"UNIVERSAL_POWER"
"1","(-13600,2850)","0","pure_quanta_power","I55";
;
ROOM"AUX_SW"
HDL_POWER"HSC_VDD"
BOM_COST"MIO_VRD_SB"
CDS_LIB"pure_quanta_power";
"A"39;
%"Q_RES"
"1","(-13100,2775)","0","pure_quanta","I56";
;
LOCATION"PR2106"
$SEC"1"
CDS_SEC"1"
VALUE"10K"
ROOM"HSC BOM1"
WATTAGE"1/16W"
TOLERANCE"1%"
PACK_TYPE"0402LF"
MATERIAL"CHIP"
CDS_LIB"pure_quanta"
PART_NUMBER"CS31002FB08";
"B"
$PN"2"20;
"A"
$PN"1"39;
%"UNIVERSAL_GND"
"1","(-12075,1925)","0","pure_quanta_power","I57";
;
HDL_POWER"AGND_HSC"
CDS_LIB"pure_quanta_power";
"A"40;
%"MP5990GMA1111Z"
"1","(-11400,3050)","0","pure_quanta","I58";
;
LOCATION"PU289"
$SEC"1"
CDS_SEC"1"
ROOM"HSC BOM1"
PART_TYPE"SMLF"
VALUE"MP5990GMA-1111-Z"
MATERIAL"IC"
CDS_LIB"pure_quanta"
NEEDS_NO_SIZE"TRUE"
CDS_LMAN_SYM_OUTLINE"-425,1125,425,-1125"
PART_NUMBER"AR0F0TP4023";
"ADDR"
$PN"23"27;
"VDD18"
$PN"19"26;
"VDD33_2"
$PN"45"11;
"VDD33_1"
$PN"17"11;
"VINSEN"
$PN"9"46;
"VIN10"
$PN"43"50;
"FLT_TYPE"
$PN"40"12;
"GND2"
$PN"44"40;
"VIN1"
$PN"1"50;
"VOUT4"
$PN"30"48;
"VOSEN"
$PN"24"49;
"VOUT10"
$PN"36"48;
"VIN9"
$PN"42"50;
"CS"
$PN"20"35;
"IMON"
$PN"21"36;
"VOUT6"
$PN"32"48;
"SS"
$PN"16"34;
"SCREF_OCWREF"
$PN"25"13;
"OCREF"
$PN"22"14;
"VTEMP"
$PN"15"33;
"VIN6"
$PN"6"50;
"VIN5"
$PN"5"50;
"ON"
$PN"38"23;
"VOUT8"
$PN"34"48;
"PG||OCW#"
$PN"13"45;
"VIN8"
$PN"8"50;
"MODE"
$PN"41"32;
"VOUT7"
$PN"33"48;
"VIN7"
$PN"7"50;
"GOK"
$PN"39"31;
"ALT# \B"
$PN"10"22;
"VOUT9"
$PN"35"48;
"VOUT5"
$PN"31"48;
"D_OC"
$PN"37"28;
"SCL"
$PN"11"16;
"VIN_UVW# \B"
$PN"14"20;
"SDA"
$PN"12"15;
"GND1"
$PN"18"40;
"VIN4"
$PN"4"50;
"VIN3"
$PN"3"50;
"EN"
$PN"26"21;
"VIN2"
$PN"2"50;
"VOUT1"
$PN"27"48;
"VOUT2"
$PN"28"48;
"VOUT3"
$PN"29"48;
%"Q_CAP"
"1","(-13175,3900)","0","pure_quanta","I59";
;
LOCATION"PC2189"
$SEC"1"
CDS_SEC"1"
VALUE"0.01UF"
ROOM"HSC BOM1"
VOLTAGE"50V"
MATERIAL"X7R"
PACK_TYPE"C0402"
TOLERANCE"10%"
CDS_LIB"pure_quanta"
PART_NUMBER"CH31006KB18";
"B"
$PN"2"38;
"A"
$PN"1"46;
%"Q_RES"
"2","(-9975,1900)","0","pure_quanta","I63";
;
LOCATION"R3933"
$SEC"1"
CDS_SEC"1"
VALUE"16.9K"
PACK_TYPE"0402LF"
MATERIAL"CHIP"
TOLERANCE"1%"
WATTAGE"1/16W"
ROOM"HSC BOM1"
CDS_LIB"pure_quanta"
PART_NUMBER"CS31692FB03";
"A"
$PN"1"7;
"B"
$PN"2"45;
%"UNIVERSAL_POWER"
"1","(-9975,2100)","0","pure_quanta_power","I64";
;
HDL_POWER"P12V_AUX"
CDS_LIB"pure_quanta_power"
BOM_COST"MIO_VRD_SB";
"A"7;
%"Q_RES"
"1","(-10150,2975)","0","pure_quanta","I65";
;
LOCATION"PR1131"
$SEC"1"
CDS_SEC"1"
MATERIAL"CHIP"
PACK_TYPE"0402LF"
ROOM"HSC BOM1"
WATTAGE"1/16W"
TOLERANCE"0.1%"
VALUE"2K"
CDS_LIB"pure_quanta"
PART_NUMBER"CS22002BB07";
"B"
$PN"2"8;
"A"
$PN"1"35;
%"UNIVERSAL_GND"
"1","(-9625,2875)","0","pure_quanta_power","I66";
;
HDL_POWER"AGND_HSC"
CDS_LIB"pure_quanta_power";
"A"8;
%"UNIVERSAL_GND"
"1","(-9775,3675)","0","pure_quanta_power","I69";
;
HDL_POWER"AGND_HSC"
CDS_LIB"pure_quanta_power";
"A"47;
%"Q_RES"
"2","(-10250,3975)","0","pure_quanta","I70";
;
LOCATION"PR3932"
$SEC"1"
CDS_SEC"1"
VALUE"4.99K"
TOLERANCE"0.1%"
WATTAGE"1/16W"
MATERIAL"CHIP"
PACK_TYPE"0402LF"
ROOM"HSC BOM1"
CDS_LIB"pure_quanta"
PART_NUMBER"CS24992BB04";
"A"
$PN"1"49;
"B"
$PN"2"47;
%"Q_RES"
"2","(-10325,4425)","0","pure_quanta","I71";
;
LOCATION"PR3931"
$SEC"1"
CDS_SEC"1"
PACK_TYPE"0402LF"
MATERIAL"CHIP"
WATTAGE"1/16W"
TOLERANCE"0.1%"
VALUE"75K"
ROOM"HSC BOM1"
CDS_LIB"pure_quanta"
PART_NUMBER"CS37502BB01";
"A"
$PN"1"48;
"B"
$PN"2"49;
%"Q_CAP"
"1","(-9775,3975)","0","pure_quanta","I72";
;
LOCATION"PC2190"
$SEC"1"
CDS_SEC"1"
VOLTAGE"50V"
VALUE"0.01UF"
ROOM"HSC BOM1"
MATERIAL"X7R"
PACK_TYPE"C0402"
TOLERANCE"10%"
CDS_LIB"pure_quanta"
PART_NUMBER"CH31006KB18";
"B"
$PN"2"47;
"A"
$PN"1"49;
%"UNIVERSAL_GND"
"1","(-9500,2000)","0","pure_quanta_power","I74";
;
HDL_POWER"AGND_HSC"
CDS_LIB"pure_quanta_power";
"A"9;
%"Q_CAP"
"1","(-9500,2175)","0","pure_quanta","I75";
;
LOCATION"PC2191"
$SEC"1"
CDS_SEC"1"
ROOM"HSC BOM1"
VALUE"0.068UF"
VOLTAGE"16V"
MATERIAL"X7R"
PACK_TYPE"0402"
CDS_LIB"pure_quanta"
TOLERANCE"10%"
PART_NUMBER"CH3683K1B09";
"B"
$PN"2"9;
"A"
$PN"1"34;
%"UNIVERSAL_GND"
"1","(-8625,2100)","0","pure_quanta_power","I77";
;
HDL_POWER"AGND_HSC"
CDS_LIB"pure_quanta_power";
"A"41;
%"Q_CAP"
"1","(-8925,2425)","0","pure_quanta","I78";
;
LOCATION"PC2192"
$SEC"1"
CDS_SEC"1"
PACK_TYPE"C0402"
VOLTAGE"50V"
MATERIAL"X7R"
VALUE"0.001UF"
ROOM"HSC BOM1"
CDS_LIB"pure_quanta"
TOLERANCE"10%"
PART_NUMBER"CH30106KB19";
"B"
$PN"2"41;
"A"
$PN"1"33;
%"Q_RES"
"1","(-8950,3575)","0","pure_quanta","I79";
;
LOCATION"R2588"
$SEC"1"
CDS_SEC"1"
ROOM"HSC BOM1"
PACK_TYPE"0402LF"
WATTAGE"1/16W"
MATERIAL"CHIP"
TOLERANCE"1%"
VALUE"22"
CDS_LIB"pure_quanta"
PART_NUMBER"CS02202FB02";
"B"
$PN"2"29;
"A"
$PN"1"31;
%"Q_RES"
"1","(-8950,3400)","0","pure_quanta","I80";
;
LOCATION"R3934"
$SEC"1"
CDS_SEC"1"
TOLERANCE"1%"
PACK_TYPE"0402LF"
ROOM"HSC BOM1"
WATTAGE"1/16W"
MATERIAL"CHIP"
VALUE"22"
CDS_LIB"pure_quanta"
PART_NUMBER"CS02202FB02";
"B"
$PN"2"30;
"A"
$PN"1"28;
%"Q_RES"
"2","(-8450,2450)","0","pure_quanta","I81";
;
LOCATION"PR3935"
$SEC"1"
CDS_SEC"1"
WATTAGE"1/16W"
VALUE"10K"
TOLERANCE"1%"
ROOM"HSC BOM1"
PACK_TYPE"0402LF"
MATERIAL"CHIP"
CDS_LIB"pure_quanta"
PART_NUMBER"CS31002FB08";
"A"
$PN"1"33;
"B"
$PN"2"41;
%"UNIVERSAL_GND"
"1","(-7625,2600)","0","pure_quanta_power","I83";
;
HDL_POWER"AGND_HSC"
CDS_LIB"pure_quanta_power";
"A"42;
%"Q_CAP"
"1","(-8100,2850)","0","pure_quanta","I84";
;
LOCATION"PC2193"
$SEC"1"
CDS_SEC"1"
PACK_TYPE"C0402"
VOLTAGE"25V"
VALUE"0.047UF"
ROOM"HSC BOM1"
MATERIAL"X7R"
TOLERANCE"10%"
CDS_LIB"pure_quanta"
PART_NUMBER"CH3474K1B04";
"B"
$PN"2"42;
"A"
$PN"1"36;
%"Q_RES"
"1","(-8125,3275)","0","pure_quanta","I85";
;
LOCATION"PR3937"
$SEC"1"
CDS_SEC"1"
PACK_TYPE"0402LF"
TOLERANCE"1%"
ROOM"HSC BOM1"
WATTAGE"1/16W"
MATERIAL"CHIP"
VALUE"120K"
CDS_LIB"pure_quanta"
PART_NUMBER"CS41202FB05";
"B"
$PN"2"10;
"A"
$PN"1"32;
%"Q_RES"
"2","(-7625,2875)","0","pure_quanta","I86";
;
LOCATION"PR1133"
$SEC"1"
CDS_SEC"1"
VALUE"2K"
TOLERANCE"0.1%"
ROOM"HSC BOM1"
PACK_TYPE"0402LF"
MATERIAL"CHIP"
WATTAGE"1/16W"
CDS_LIB"pure_quanta"
PART_NUMBER"CS22002BB07";
"A"
$PN"1"36;
"B"
$PN"2"42;
%"UNIVERSAL_GND"
"1","(-7550,3200)","0","pure_quanta_power","I87";
;
HDL_POWER"AGND_HSC"
CDS_LIB"pure_quanta_power";
"A"10;
%"GND"
"1","(-9175,3725)","0","pure_quanta_power","I88";
;
SIZE"1B"
CDS_LIB"pure_quanta_power"
HDL_POWER"GND";
"A<SIZE-1..0>\NAC"43;
%"SS15P3SM386A"
"1","(-9175,4225)","1","pure_quanta","I89";
;
LOCATION"PD111"
$SEC"1"
CDS_SEC"1"
PART_TYPE"SMLF"
VALUE"SS15P3S-M3/86A"
MATERIAL"IC"
ROOM"HSC BOM1"
CDS_LIB"pure_quanta"
NEEDS_NO_SIZE"TRUE"
CDS_LMAN_SYM_OUTLINE"-125,100,125,-100"
PART_NUMBER"BC015P3SZ00";
"ANODE_2"
$PN"2"43;
"CATHODE"
$PN"K"48;
"ANODE_1"
$PN"1"43;
%"UNIVERSAL_POWER"
"1","(-8575,4800)","0","pure_quanta_power","I90";
;
HDL_POWER"P12V_AUX"
BOM_COST"MIO_VRD_SB"
CDS_LIB"pure_quanta_power";
"A"48;
%"Q_RES"
"2","(-8425,3900)","0","pure_quanta","I91";
;
LOCATION"R3936"
$SEC"1"
CDS_SEC"1"
PACK_TYPE"0402LF"
MATERIAL"CHIP"
WATTAGE"1/16W"
TOLERANCE"1%"
ROOM"HSC BOM1"
VALUE"4.7K"
CDS_LIB"pure_quanta"
PART_NUMBER"CS24702FB06";
"A"
$PN"1"44;
"B"
$PN"2"30;
%"UNIVERSAL_POWER"
"1","(-8225,4250)","0","pure_quanta_power","I92";
;
HDL_POWER"HSC_VDD"
CDS_LIB"pure_quanta_power"
BOM_COST"MIO_VRD_SB";
"A"44;
%"Q_RES"
"1","(-8000,3900)","1","pure_quanta","I99";
;
LOCATION"R2587"
$SEC"1"
CDS_SEC"1"
MATERIAL"CHIP"
WATTAGE"1/16W"
TOLERANCE"1%"
VALUE"1K"
PACK_TYPE"0402LF"
ROOM"HSC BOM1"
CDS_LIB"pure_quanta"
PART_NUMBER"CS21002FB06";
"B"
$PN"2"44;
"A"
$PN"1"29;
END.
